(kicad_pcb
	(version 20260206)
	(generator "pcbnew")
	(generator_version "10.0")
	(general
		(thickness 1.6)
		(legacy_teardrops no)
	)
	(paper "A4")
	(title_block
		(title "Wiwynn_Tioga_Pass_MB.brd")
		(comment 1 "Tioga Pass / footprint 320 of 4770 (J1B1), pads 1-123 of 291")
	)
	(layers
		(0 "F.Cu" signal "TOP")
		(4 "In1.Cu" signal "L2GND")
		(6 "In2.Cu" signal "L3")
		(8 "In3.Cu" signal "L4GND")
		(10 "In4.Cu" signal "L5")
		(12 "In5.Cu" signal "L6GND")
		(14 "In6.Cu" signal "L7VCC")
		(16 "In7.Cu" signal "L8VCC")
		(18 "In8.Cu" signal "L9GND")
		(20 "In9.Cu" signal "L10")
		(22 "In10.Cu" signal "L11GND")
		(24 "In11.Cu" signal "L12")
		(26 "In12.Cu" signal "L13GND")
		(2 "B.Cu" signal "BOTTOM")
		(9 "F.Adhes" user "F.Adhesive")
		(11 "B.Adhes" user "B.Adhesive")
		(13 "F.Paste" user "Package Geometry/Pastemask Top")
		(15 "B.Paste" user "Package Geometry/Pastemask Bottom")
		(5 "F.SilkS" user "Ref Des/Silkscreen Top")
		(7 "B.SilkS" user "Ref Des/Silkscreen Bottom")
		(1 "F.Mask" user "Board Geometry/Soldermask Top")
		(3 "B.Mask" user "Board Geometry/Soldermask Bottom")
		(17 "Dwgs.User" user "User.Drawings")
		(19 "Cmts.User" user "User.Comments")
		(21 "Eco1.User" user "User.Eco1")
		(23 "Eco2.User" user "User.Eco2")
		(25 "Edge.Cuts" user "Board Geometry/Outline")
		(27 "Margin" user)
		(31 "F.CrtYd" user "Package Geometry/Place Bound Top")
		(29 "B.CrtYd" user "Package Geometry/Place Bound Bottom")
		(35 "F.Fab" user "Ref Des/Assembly Top")
		(33 "B.Fab" user "Ref Des/Assembly Bottom")
	)
	(footprint ""
		(layer "F.Cu")
		(at 29.699458 -133.0706 90)
		(property "Reference" "J1B1"
			(at -4.960112 38.372542 0)
			(unlocked yes)
			(layer "F.SilkS")
			(effects
				(font
					(size 0.7874 0.5842)
					(thickness 0.1524)
				)
				(justify left)
			)
		)
		(property "Value" ""
			(at 0 0 90)
			(layer "F.Fab")
			(effects
				(font
					(size 1.27 1.27)
				)
			)
		)
		(duplicate_pad_numbers_are_jumpers no)
		(pad "" thru_hole circle
			(at 2.29997 -5.649976 90)
			(size 2.8194 2.8194)
			(drill 2.4384)
			(layers "*.Cu" "*.Mask")
			(remove_unused_layers no)
			(clearance 0.127)
			(thermal_gap 0.127)
		)
		(pad "" thru_hole oval
			(at 2.29997 68.90004 90)
			(size 2.8194 1.5748)
			(drill oval 2.4384 1.1938)
			(layers "*.Cu" "*.Mask")
			(remove_unused_layers no)
			(clearance 0.127)
			(thermal_gap 0.127)
		)
		(pad "" thru_hole circle
			(at 2.29997 132.299964 90)
			(size 2.8194 2.8194)
			(drill 2.4384)
			(layers "*.Cu" "*.Mask")
			(remove_unused_layers no)
			(clearance 0.127)
			(thermal_gap 0.127)
		)
		(pad "1" smd rect
			(at 0 0 90)
			(size 1.8034 0.508)
			(layers "F.Cu" "F.Mask" "F.Paste")
			(net "P12V_NVDIMM_KLM")
		)
		(pad "2" smd rect
			(at 0 0.849884 90)
			(size 1.8034 0.508)
			(layers "F.Cu" "F.Mask" "F.Paste")
			(net "GND")
		)
		(pad "3" smd rect
			(at 0 1.700022 90)
			(size 1.8034 0.508)
			(layers "F.Cu" "F.Mask" "F.Paste")
			(net "M_K_DQ<5>")
		)
		(pad "4" smd rect
			(at 0 2.549906 90)
			(size 1.8034 0.508)
			(layers "F.Cu" "F.Mask" "F.Paste")
			(net "GND")
		)
		(pad "5" smd rect
			(at 0 3.400044 90)
			(size 1.8034 0.508)
			(layers "F.Cu" "F.Mask" "F.Paste")
			(net "M_K_DQ<1>")
		)
		(pad "6" smd rect
			(at 0 4.249928 90)
			(size 1.8034 0.508)
			(layers "F.Cu" "F.Mask" "F.Paste")
			(net "GND")
		)
		(pad "7" smd rect
			(at 0 5.100066 90)
			(size 1.8034 0.508)
			(layers "F.Cu" "F.Mask" "F.Paste")
			(net "M_K_DQS_DP<9>")
		)
		(pad "8" smd rect
			(at 0 5.94995 90)
			(size 1.8034 0.508)
			(layers "F.Cu" "F.Mask" "F.Paste")
			(net "M_K_DQS_DN<9>")
		)
		(pad "9" smd rect
			(at 0 6.800088 90)
			(size 1.8034 0.508)
			(layers "F.Cu" "F.Mask" "F.Paste")
			(net "GND")
		)
		(pad "10" smd rect
			(at 0 7.649972 90)
			(size 1.8034 0.508)
			(layers "F.Cu" "F.Mask" "F.Paste")
			(net "M_K_DQ<7>")
		)
		(pad "11" smd rect
			(at 0 8.50011 90)
			(size 1.8034 0.508)
			(layers "F.Cu" "F.Mask" "F.Paste")
			(net "GND")
		)
		(pad "12" smd rect
			(at 0 9.349994 90)
			(size 1.8034 0.508)
			(layers "F.Cu" "F.Mask" "F.Paste")
			(net "M_K_DQ<3>")
		)
		(pad "13" smd rect
			(at 0 10.199878 90)
			(size 1.8034 0.508)
			(layers "F.Cu" "F.Mask" "F.Paste")
			(net "GND")
		)
		(pad "14" smd rect
			(at 0 11.050016 90)
			(size 1.8034 0.508)
			(layers "F.Cu" "F.Mask" "F.Paste")
			(net "M_K_DQ<13>")
		)
		(pad "15" smd rect
			(at 0 11.8999 90)
			(size 1.8034 0.508)
			(layers "F.Cu" "F.Mask" "F.Paste")
			(net "GND")
		)
		(pad "16" smd rect
			(at 0 12.750038 90)
			(size 1.8034 0.508)
			(layers "F.Cu" "F.Mask" "F.Paste")
			(net "M_K_DQ<9>")
		)
		(pad "17" smd rect
			(at 0 13.599922 90)
			(size 1.8034 0.508)
			(layers "F.Cu" "F.Mask" "F.Paste")
			(net "GND")
		)
		(pad "18" smd rect
			(at 0 14.45006 90)
			(size 1.8034 0.508)
			(layers "F.Cu" "F.Mask" "F.Paste")
			(net "M_K_DQS_DP<10>")
		)
		(pad "19" smd rect
			(at 0 15.299944 90)
			(size 1.8034 0.508)
			(layers "F.Cu" "F.Mask" "F.Paste")
			(net "M_K_DQS_DN<10>")
		)
		(pad "20" smd rect
			(at 0 16.150082 90)
			(size 1.8034 0.508)
			(layers "F.Cu" "F.Mask" "F.Paste")
			(net "GND")
		)
		(pad "21" smd rect
			(at 0 16.999966 90)
			(size 1.8034 0.508)
			(layers "F.Cu" "F.Mask" "F.Paste")
			(net "M_K_DQ<15>")
		)
		(pad "22" smd rect
			(at 0 17.850104 90)
			(size 1.8034 0.508)
			(layers "F.Cu" "F.Mask" "F.Paste")
			(net "GND")
		)
		(pad "23" smd rect
			(at 0 18.699988 90)
			(size 1.8034 0.508)
			(layers "F.Cu" "F.Mask" "F.Paste")
			(net "M_K_DQ<11>")
		)
		(pad "24" smd rect
			(at 0 19.550126 90)
			(size 1.8034 0.508)
			(layers "F.Cu" "F.Mask" "F.Paste")
			(net "GND")
		)
		(pad "25" smd rect
			(at 0 20.40001 90)
			(size 1.8034 0.508)
			(layers "F.Cu" "F.Mask" "F.Paste")
			(net "M_K_DQ<21>")
		)
		(pad "26" smd rect
			(at 0 21.249894 90)
			(size 1.8034 0.508)
			(layers "F.Cu" "F.Mask" "F.Paste")
			(net "GND")
		)
		(pad "27" smd rect
			(at 0 22.100032 90)
			(size 1.8034 0.508)
			(layers "F.Cu" "F.Mask" "F.Paste")
			(net "M_K_DQ<17>")
		)
		(pad "28" smd rect
			(at 0 22.949916 90)
			(size 1.8034 0.508)
			(layers "F.Cu" "F.Mask" "F.Paste")
			(net "GND")
		)
		(pad "29" smd rect
			(at 0 23.800054 90)
			(size 1.8034 0.508)
			(layers "F.Cu" "F.Mask" "F.Paste")
			(net "M_K_DQS_DP<11>")
		)
		(pad "30" smd rect
			(at 0 24.649938 90)
			(size 1.8034 0.508)
			(layers "F.Cu" "F.Mask" "F.Paste")
			(net "M_K_DQS_DN<11>")
		)
		(pad "31" smd rect
			(at 0 25.500076 90)
			(size 1.8034 0.508)
			(layers "F.Cu" "F.Mask" "F.Paste")
			(net "GND")
		)
		(pad "32" smd rect
			(at 0 26.34996 90)
			(size 1.8034 0.508)
			(layers "F.Cu" "F.Mask" "F.Paste")
			(net "M_K_DQ<23>")
		)
		(pad "33" smd rect
			(at 0 27.200098 90)
			(size 1.8034 0.508)
			(layers "F.Cu" "F.Mask" "F.Paste")
			(net "GND")
		)
		(pad "34" smd rect
			(at 0 28.049982 90)
			(size 1.8034 0.508)
			(layers "F.Cu" "F.Mask" "F.Paste")
			(net "M_K_DQ<19>")
		)
		(pad "35" smd rect
			(at 0 28.90012 90)
			(size 1.8034 0.508)
			(layers "F.Cu" "F.Mask" "F.Paste")
			(net "GND")
		)
		(pad "36" smd rect
			(at 0 29.750004 90)
			(size 1.8034 0.508)
			(layers "F.Cu" "F.Mask" "F.Paste")
			(net "M_K_DQ<29>")
		)
		(pad "37" smd rect
			(at 0 30.599888 90)
			(size 1.8034 0.508)
			(layers "F.Cu" "F.Mask" "F.Paste")
			(net "GND")
		)
		(pad "38" smd rect
			(at 0 31.450026 90)
			(size 1.8034 0.508)
			(layers "F.Cu" "F.Mask" "F.Paste")
			(net "M_K_DQ<25>")
		)
		(pad "39" smd rect
			(at 0 32.29991 90)
			(size 1.8034 0.508)
			(layers "F.Cu" "F.Mask" "F.Paste")
			(net "GND")
		)
		(pad "40" smd rect
			(at 0 33.150048 90)
			(size 1.8034 0.508)
			(layers "F.Cu" "F.Mask" "F.Paste")
			(net "M_K_DQS_DP<12>")
		)
		(pad "41" smd rect
			(at 0 33.999932 90)
			(size 1.8034 0.508)
			(layers "F.Cu" "F.Mask" "F.Paste")
			(net "M_K_DQS_DN<12>")
		)
		(pad "42" smd rect
			(at 0 34.85007 90)
			(size 1.8034 0.508)
			(layers "F.Cu" "F.Mask" "F.Paste")
			(net "GND")
		)
		(pad "43" smd rect
			(at 0 35.699954 90)
			(size 1.8034 0.508)
			(layers "F.Cu" "F.Mask" "F.Paste")
			(net "M_K_DQ<31>")
		)
		(pad "44" smd rect
			(at 0 36.550092 90)
			(size 1.8034 0.508)
			(layers "F.Cu" "F.Mask" "F.Paste")
			(net "GND")
		)
		(pad "45" smd rect
			(at 0 37.399976 90)
			(size 1.8034 0.508)
			(layers "F.Cu" "F.Mask" "F.Paste")
			(net "M_K_DQ<27>")
		)
		(pad "46" smd rect
			(at 0 38.250114 90)
			(size 1.8034 0.508)
			(layers "F.Cu" "F.Mask" "F.Paste")
			(net "GND")
		)
		(pad "47" smd rect
			(at 0 39.099998 90)
			(size 1.8034 0.508)
			(layers "F.Cu" "F.Mask" "F.Paste")
			(net "M_K_ECC<5>")
		)
		(pad "48" smd rect
			(at 0 39.949882 90)
			(size 1.8034 0.508)
			(layers "F.Cu" "F.Mask" "F.Paste")
			(net "GND")
		)
		(pad "49" smd rect
			(at 0 40.80002 90)
			(size 1.8034 0.508)
			(layers "F.Cu" "F.Mask" "F.Paste")
			(net "M_K_ECC<1>")
		)
		(pad "50" smd rect
			(at 0 41.649904 90)
			(size 1.8034 0.508)
			(layers "F.Cu" "F.Mask" "F.Paste")
			(net "GND")
		)
		(pad "51" smd rect
			(at 0 42.500042 90)
			(size 1.8034 0.508)
			(layers "F.Cu" "F.Mask" "F.Paste")
			(net "M_K_DQS_DP<17>")
		)
		(pad "52" smd rect
			(at 0 43.349926 90)
			(size 1.8034 0.508)
			(layers "F.Cu" "F.Mask" "F.Paste")
			(net "M_K_DQS_DN<17>")
		)
		(pad "53" smd rect
			(at 0 44.200064 90)
			(size 1.8034 0.508)
			(layers "F.Cu" "F.Mask" "F.Paste")
			(net "GND")
		)
		(pad "54" smd rect
			(at 0 45.049948 90)
			(size 1.8034 0.508)
			(layers "F.Cu" "F.Mask" "F.Paste")
			(net "M_K_ECC<7>")
		)
		(pad "55" smd rect
			(at 0 45.900086 90)
			(size 1.8034 0.508)
			(layers "F.Cu" "F.Mask" "F.Paste")
			(net "GND")
		)
		(pad "56" smd rect
			(at 0 46.74997 90)
			(size 1.8034 0.508)
			(layers "F.Cu" "F.Mask" "F.Paste")
			(net "M_K_ECC<3>")
		)
		(pad "57" smd rect
			(at 0 47.600108 90)
			(size 1.8034 0.508)
			(layers "F.Cu" "F.Mask" "F.Paste")
			(net "GND")
		)
		(pad "58" smd rect
			(at 0 48.449992 90)
			(size 1.8034 0.508)
			(layers "F.Cu" "F.Mask" "F.Paste")
			(net "M_KLM_RST_N")
		)
		(pad "59" smd rect
			(at 0 49.299876 90)
			(size 1.8034 0.508)
			(layers "F.Cu" "F.Mask" "F.Paste")
			(net "PVDDQ_KLM")
		)
		(pad "60" smd rect
			(at 0 50.150014 90)
			(size 1.8034 0.508)
			(layers "F.Cu" "F.Mask" "F.Paste")
			(net "M_K_CKE<0>")
		)
		(pad "61" smd rect
			(at 0 50.999898 90)
			(size 1.8034 0.508)
			(layers "F.Cu" "F.Mask" "F.Paste")
			(net "PVDDQ_KLM")
		)
		(pad "62" smd rect
			(at 0 51.850036 90)
			(size 1.8034 0.508)
			(layers "F.Cu" "F.Mask" "F.Paste")
			(net "M_K_ACT_N")
		)
		(pad "63" smd rect
			(at 0 52.69992 90)
			(size 1.8034 0.508)
			(layers "F.Cu" "F.Mask" "F.Paste")
			(net "M_K_BG<0>")
		)
		(pad "64" smd rect
			(at 0 53.550058 90)
			(size 1.8034 0.508)
			(layers "F.Cu" "F.Mask" "F.Paste")
			(net "PVDDQ_KLM")
		)
		(pad "65" smd rect
			(at 0 54.399942 90)
			(size 1.8034 0.508)
			(layers "F.Cu" "F.Mask" "F.Paste")
			(net "M_K_MA<12>")
		)
		(pad "66" smd rect
			(at 0 55.25008 90)
			(size 1.8034 0.508)
			(layers "F.Cu" "F.Mask" "F.Paste")
			(net "M_K_MA<9>")
		)
		(pad "67" smd rect
			(at 0 56.099964 90)
			(size 1.8034 0.508)
			(layers "F.Cu" "F.Mask" "F.Paste")
			(net "PVDDQ_KLM")
		)
		(pad "68" smd rect
			(at 0 56.950102 90)
			(size 1.8034 0.508)
			(layers "F.Cu" "F.Mask" "F.Paste")
			(net "M_K_MA<8>")
		)
		(pad "69" smd rect
			(at 0 57.799986 90)
			(size 1.8034 0.508)
			(layers "F.Cu" "F.Mask" "F.Paste")
			(net "M_K_MA<6>")
		)
		(pad "70" smd rect
			(at 0 58.650124 90)
			(size 1.8034 0.508)
			(layers "F.Cu" "F.Mask" "F.Paste")
			(net "PVDDQ_KLM")
		)
		(pad "71" smd rect
			(at 0 59.500008 90)
			(size 1.8034 0.508)
			(layers "F.Cu" "F.Mask" "F.Paste")
			(net "M_K_MA<3>")
		)
		(pad "72" smd rect
			(at 0 60.349892 90)
			(size 1.8034 0.508)
			(layers "F.Cu" "F.Mask" "F.Paste")
			(net "M_K_MA<1>")
		)
		(pad "73" smd rect
			(at 0 61.20003 90)
			(size 1.8034 0.508)
			(layers "F.Cu" "F.Mask" "F.Paste")
			(net "PVDDQ_KLM")
		)
		(pad "74" smd rect
			(at 0 62.049914 90)
			(size 1.8034 0.508)
			(layers "F.Cu" "F.Mask" "F.Paste")
			(net "M_K_CLK_DP<0>")
		)
		(pad "75" smd rect
			(at 0 62.900052 90)
			(size 1.8034 0.508)
			(layers "F.Cu" "F.Mask" "F.Paste")
			(net "M_K_CLK_DN<0>")
		)
		(pad "76" smd rect
			(at 0 63.749936 90)
			(size 1.8034 0.508)
			(layers "F.Cu" "F.Mask" "F.Paste")
			(net "PVDDQ_KLM")
		)
		(pad "77" smd rect
			(at 0 64.600074 90)
			(size 1.8034 0.508)
			(layers "F.Cu" "F.Mask" "F.Paste")
			(net "PVTT_KLM")
		)
		(pad "78" smd rect
			(at 0 70.550024 90)
			(size 1.8034 0.508)
			(layers "F.Cu" "F.Mask" "F.Paste")
			(net "FM_DIMM_EVENT_COD_N")
		)
		(pad "79" smd rect
			(at 0 71.399908 90)
			(size 1.8034 0.508)
			(layers "F.Cu" "F.Mask" "F.Paste")
			(net "M_K_MA<0>")
		)
		(pad "80" smd rect
			(at 0 72.250046 90)
			(size 1.8034 0.508)
			(layers "F.Cu" "F.Mask" "F.Paste")
			(net "PVDDQ_KLM")
		)
		(pad "81" smd rect
			(at 0 73.09993 90)
			(size 1.8034 0.508)
			(layers "F.Cu" "F.Mask" "F.Paste")
			(net "M_K_BA<0>")
		)
		(pad "82" smd rect
			(at 0 73.950068 90)
			(size 1.8034 0.508)
			(layers "F.Cu" "F.Mask" "F.Paste")
			(net "M_K_MA<16>")
		)
		(pad "83" smd rect
			(at 0 74.799952 90)
			(size 1.8034 0.508)
			(layers "F.Cu" "F.Mask" "F.Paste")
			(net "PVDDQ_KLM")
		)
		(pad "84" smd rect
			(at 0 75.65009 90)
			(size 1.8034 0.508)
			(layers "F.Cu" "F.Mask" "F.Paste")
			(net "M_K_CS_N<0>")
		)
		(pad "85" smd rect
			(at 0 76.499974 90)
			(size 1.8034 0.508)
			(layers "F.Cu" "F.Mask" "F.Paste")
			(net "PVDDQ_KLM")
		)
		(pad "86" smd rect
			(at 0 77.350112 90)
			(size 1.8034 0.508)
			(layers "F.Cu" "F.Mask" "F.Paste")
			(net "M_K_MA<15>")
		)
		(pad "87" smd rect
			(at 0 78.199996 90)
			(size 1.8034 0.508)
			(layers "F.Cu" "F.Mask" "F.Paste")
			(net "M_K_ODT<0>")
		)
		(pad "88" smd rect
			(at 0 79.04988 90)
			(size 1.8034 0.508)
			(layers "F.Cu" "F.Mask" "F.Paste")
			(net "PVDDQ_KLM")
		)
		(pad "89" smd rect
			(at 0 79.900018 90)
			(size 1.8034 0.508)
			(layers "F.Cu" "F.Mask" "F.Paste")
			(net "M_K_CS_N<1>")
		)
		(pad "90" smd rect
			(at 0 80.749902 90)
			(size 1.8034 0.508)
			(layers "F.Cu" "F.Mask" "F.Paste")
			(net "PVDDQ_KLM")
		)
		(pad "91" smd rect
			(at 0 81.60004 90)
			(size 1.8034 0.508)
			(layers "F.Cu" "F.Mask" "F.Paste")
			(net "M_K_ODT<1>")
		)
		(pad "92" smd rect
			(at 0 82.449924 90)
			(size 1.8034 0.508)
			(layers "F.Cu" "F.Mask" "F.Paste")
			(net "PVDDQ_KLM")
		)
		(pad "93" smd rect
			(at 0 83.300062 90)
			(size 1.8034 0.508)
			(layers "F.Cu" "F.Mask" "F.Paste")
			(net "M_K_CS_N<2>")
		)
		(pad "94" smd rect
			(at 0 84.149946 90)
			(size 1.8034 0.508)
			(layers "F.Cu" "F.Mask" "F.Paste")
			(net "GND")
		)
		(pad "95" smd rect
			(at 0 85.000084 90)
			(size 1.8034 0.508)
			(layers "F.Cu" "F.Mask" "F.Paste")
			(net "M_K_DQ<37>")
		)
		(pad "96" smd rect
			(at 0 85.849968 90)
			(size 1.8034 0.508)
			(layers "F.Cu" "F.Mask" "F.Paste")
			(net "GND")
		)
		(pad "97" smd rect
			(at 0 86.700106 90)
			(size 1.8034 0.508)
			(layers "F.Cu" "F.Mask" "F.Paste")
			(net "M_K_DQ<33>")
		)
		(pad "98" smd rect
			(at 0 87.54999 90)
			(size 1.8034 0.508)
			(layers "F.Cu" "F.Mask" "F.Paste")
			(net "GND")
		)
		(pad "99" smd rect
			(at 0 88.399874 90)
			(size 1.8034 0.508)
			(layers "F.Cu" "F.Mask" "F.Paste")
			(net "M_K_DQS_DP<13>")
		)
		(pad "100" smd rect
			(at 0 89.250012 90)
			(size 1.8034 0.508)
			(layers "F.Cu" "F.Mask" "F.Paste")
			(net "M_K_DQS_DN<13>")
		)
		(pad "101" smd rect
			(at 0 90.099896 90)
			(size 1.8034 0.508)
			(layers "F.Cu" "F.Mask" "F.Paste")
			(net "GND")
		)
		(pad "102" smd rect
			(at 0 90.950034 90)
			(size 1.8034 0.508)
			(layers "F.Cu" "F.Mask" "F.Paste")
			(net "M_K_DQ<39>")
		)
		(pad "103" smd rect
			(at 0 91.799918 90)
			(size 1.8034 0.508)
			(layers "F.Cu" "F.Mask" "F.Paste")
			(net "GND")
		)
		(pad "104" smd rect
			(at 0 92.650056 90)
			(size 1.8034 0.508)
			(layers "F.Cu" "F.Mask" "F.Paste")
			(net "M_K_DQ<35>")
		)
		(pad "105" smd rect
			(at 0 93.49994 90)
			(size 1.8034 0.508)
			(layers "F.Cu" "F.Mask" "F.Paste")
			(net "GND")
		)
		(pad "106" smd rect
			(at 0 94.350078 90)
			(size 1.8034 0.508)
			(layers "F.Cu" "F.Mask" "F.Paste")
			(net "M_K_DQ<45>")
		)
		(pad "107" smd rect
			(at 0 95.199962 90)
			(size 1.8034 0.508)
			(layers "F.Cu" "F.Mask" "F.Paste")
			(net "GND")
		)
		(pad "108" smd rect
			(at 0 96.0501 90)
			(size 1.8034 0.508)
			(layers "F.Cu" "F.Mask" "F.Paste")
			(net "M_K_DQ<41>")
		)
		(pad "109" smd rect
			(at 0 96.899984 90)
			(size 1.8034 0.508)
			(layers "F.Cu" "F.Mask" "F.Paste")
			(net "GND")
		)
		(pad "110" smd rect
			(at 0 97.750122 90)
			(size 1.8034 0.508)
			(layers "F.Cu" "F.Mask" "F.Paste")
			(net "M_K_DQS_DP<14>")
		)
		(pad "111" smd rect
			(at 0 98.600006 90)
			(size 1.8034 0.508)
			(layers "F.Cu" "F.Mask" "F.Paste")
			(net "M_K_DQS_DN<14>")
		)
		(pad "112" smd rect
			(at 0 99.44989 90)
			(size 1.8034 0.508)
			(layers "F.Cu" "F.Mask" "F.Paste")
			(net "GND")
		)
		(pad "113" smd rect
			(at 0 100.300028 90)
			(size 1.8034 0.508)
			(layers "F.Cu" "F.Mask" "F.Paste")
			(net "M_K_DQ<47>")
		)
		(pad "114" smd rect
			(at 0 101.149912 90)
			(size 1.8034 0.508)
			(layers "F.Cu" "F.Mask" "F.Paste")
			(net "GND")
		)
		(pad "115" smd rect
			(at 0 102.00005 90)
			(size 1.8034 0.508)
			(layers "F.Cu" "F.Mask" "F.Paste")
			(net "M_K_DQ<43>")
		)
		(pad "116" smd rect
			(at 0 102.849934 90)
			(size 1.8034 0.508)
			(layers "F.Cu" "F.Mask" "F.Paste")
			(net "GND")
		)
		(pad "117" smd rect
			(at 0 103.700072 90)
			(size 1.8034 0.508)
			(layers "F.Cu" "F.Mask" "F.Paste")
			(net "M_K_DQ<53>")
		)
		(pad "118" smd rect
			(at 0 104.549956 90)
			(size 1.8034 0.508)
			(layers "F.Cu" "F.Mask" "F.Paste")
			(net "GND")
		)
		(pad "119" smd rect
			(at 0 105.400094 90)
			(size 1.8034 0.508)
			(layers "F.Cu" "F.Mask" "F.Paste")
			(net "M_K_DQ<49>")
		)
		(pad "120" smd rect
			(at 0 106.249978 90)
			(size 1.8034 0.508)
			(layers "F.Cu" "F.Mask" "F.Paste")
			(net "GND")
		)
	)
)
